# BASEBOARD_FAB2 (Tioga Pass) — schematic netlist excerpt (pin names and nets, part order shuffled) for the footprints in the layout excerpt that follows; sources: Cadence DE-HDL packaged netlist, KiCad conversion of Wiwynn_Tioga_Pass_MB.brd

J1D1  FCI-CONN12-2R-GP  pkg CONN-G5  page 195
  \1_1\  = P12V_PSU
  \1_2\  = P12V_PSU
  \1_3\  = P12V_PSU
  \2_1\  = P12V_PSU
  \2_2\  = P12V_PSU
  \2_3\  = P12V_PSU
  \3_1\  = GND
  \3_2\  = GND
  \3_3\  = GND
  \4_1\  = GND
  \4_2\  = GND
  \4_3\  = GND
  NP1  = NC

(kicad_pcb
	(version 20260206)
	(generator "pcbnew")
	(generator_version "10.0")
	(general
		(thickness 1.6)
		(legacy_teardrops no)
	)
	(paper "A4")
	(title_block
		(title "Wiwynn_Tioga_Pass_MB.brd")
		(comment 1 "Tioga Pass / footprint 1758 of 4770 (J1D1), pads 1-13 of 13")
	)
	(layers
		(0 "F.Cu" signal "TOP")
		(4 "In1.Cu" signal "L2GND")
		(6 "In2.Cu" signal "L3")
		(8 "In3.Cu" signal "L4GND")
		(10 "In4.Cu" signal "L5")
		(12 "In5.Cu" signal "L6GND")
		(14 "In6.Cu" signal "L7VCC")
		(16 "In7.Cu" signal "L8VCC")
		(18 "In8.Cu" signal "L9GND")
		(20 "In9.Cu" signal "L10")
		(22 "In10.Cu" signal "L11GND")
		(24 "In11.Cu" signal "L12")
		(26 "In12.Cu" signal "L13GND")
		(2 "B.Cu" signal "BOTTOM")
		(9 "F.Adhes" user "F.Adhesive")
		(11 "B.Adhes" user "B.Adhesive")
		(13 "F.Paste" user "Package Geometry/Pastemask Top")
		(15 "B.Paste" user "Package Geometry/Pastemask Bottom")
		(5 "F.SilkS" user "Ref Des/Silkscreen Top")
		(7 "B.SilkS" user "Ref Des/Silkscreen Bottom")
		(1 "F.Mask" user "Board Geometry/Soldermask Top")
		(3 "B.Mask" user "Board Geometry/Soldermask Bottom")
		(17 "Dwgs.User" user "User.Drawings")
		(19 "Cmts.User" user "User.Comments")
		(21 "Eco1.User" user "User.Eco1")
		(23 "Eco2.User" user "User.Eco2")
		(25 "Edge.Cuts" user "Board Geometry/Outline")
		(27 "Margin" user)
		(31 "F.CrtYd" user "Package Geometry/Place Bound Top")
		(29 "B.CrtYd" user "Package Geometry/Place Bound Bottom")
		(35 "F.Fab" user "Ref Des/Assembly Top")
		(33 "B.Fab" user "Ref Des/Assembly Bottom")
	)
	(footprint ""
		(layer "F.Cu")
		(at -1.999996 -82.63001 -90)
		(property "Reference" "J1D1"
			(at 0 0 270)
			(layer "F.SilkS")
			(hide yes)
			(effects
				(font
					(size 1.27 1.27)
				)
			)
		)
		(property "Value" "*"
			(at -18.3388 15.2273 270)
			(unlocked yes)
			(layer "F.Fab")
			(hide yes)
			(effects
				(font
					(size 1.27 1.016)
					(thickness 0.1524)
				)
			)
		)
		(property "Device Type" "FCI-CONN12-2R-GP_CONN-G5-FCI-CA"
			(at -18.3388 13.7033 270)
			(unlocked yes)
			(layer "F.Fab")
			(hide yes)
			(effects
				(font
					(size 1.27 1.016)
					(thickness 0.1524)
				)
			)
		)
		(duplicate_pad_numbers_are_jumpers no)
		(pad "" np_thru_hole circle
			(at 0 0 270)
			(size 0.254 0.254)
			(drill 2.1336)
			(layers "*.Cu" "*.Mask")
			(clearance 1.2954)
			(thermal_gap 1.2954)
		)
		(pad "1_1" thru_hole circle
			(at 2.999994 -6.999986 270)
			(size 1.1176 1.1176)
			(drill 0.749808)
			(layers "*.Cu" "*.Mask")
			(remove_unused_layers no)
			(net "P12V_PSU")
			(clearance 0.1778)
			(thermal_gap 0.1778)
		)
		(pad "1_2" thru_hole circle
			(at 2.999994 -8.999982 270)
			(size 1.1176 1.1176)
			(drill 0.749808)
			(layers "*.Cu" "*.Mask")
			(remove_unused_layers no)
			(net "P12V_PSU")
			(clearance 0.1778)
			(thermal_gap 0.1778)
		)
		(pad "1_3" thru_hole circle
			(at 2.999994 -10.999978 270)
			(size 1.1176 1.1176)
			(drill 0.749808)
			(layers "*.Cu" "*.Mask")
			(remove_unused_layers no)
			(net "P12V_PSU")
			(clearance 0.1778)
			(thermal_gap 0.1778)
		)
		(pad "2_1" thru_hole circle
			(at -2.999994 -6.999986 270)
			(size 1.1176 1.1176)
			(drill 0.749808)
			(layers "*.Cu" "*.Mask")
			(remove_unused_layers no)
			(net "P12V_PSU")
			(clearance 0.1778)
			(thermal_gap 0.1778)
		)
		(pad "2_2" thru_hole circle
			(at -2.999994 -8.999982 270)
			(size 1.1176 1.1176)
			(drill 0.749808)
			(layers "*.Cu" "*.Mask")
			(remove_unused_layers no)
			(net "P12V_PSU")
			(clearance 0.1778)
			(thermal_gap 0.1778)
		)
		(pad "2_3" thru_hole circle
			(at -2.999994 -10.999978 270)
			(size 1.1176 1.1176)
			(drill 0.749808)
			(layers "*.Cu" "*.Mask")
			(remove_unused_layers no)
			(net "P12V_PSU")
			(clearance 0.1778)
			(thermal_gap 0.1778)
		)
		(pad "3_1" thru_hole circle
			(at -2.999994 0.999998 270)
			(size 1.1176 1.1176)
			(drill 0.749808)
			(layers "*.Cu" "*.Mask")
			(remove_unused_layers no)
			(net "GND")
			(clearance 0.1778)
			(thermal_gap 0.1778)
		)
		(pad "3_2" thru_hole circle
			(at -2.999994 -0.999998 270)
			(size 1.1176 1.1176)
			(drill 0.749808)
			(layers "*.Cu" "*.Mask")
			(remove_unused_layers no)
			(net "GND")
			(clearance 0.1778)
			(thermal_gap 0.1778)
		)
		(pad "3_3" thru_hole circle
			(at -2.999994 -2.999994 270)
			(size 1.1176 1.1176)
			(drill 0.749808)
			(layers "*.Cu" "*.Mask")
			(remove_unused_layers no)
			(net "GND")
			(clearance 0.1778)
			(thermal_gap 0.1778)
		)
		(pad "4_1" thru_hole circle
			(at 2.999994 0.999998 270)
			(size 1.1176 1.1176)
			(drill 0.749808)
			(layers "*.Cu" "*.Mask")
			(remove_unused_layers no)
			(net "GND")
			(clearance 0.1778)
			(thermal_gap 0.1778)
		)
		(pad "4_2" thru_hole circle
			(at 2.999994 -0.999998 270)
			(size 1.1176 1.1176)
			(drill 0.749808)
			(layers "*.Cu" "*.Mask")
			(remove_unused_layers no)
			(net "GND")
			(clearance 0.1778)
			(thermal_gap 0.1778)
		)
		(pad "4_3" thru_hole circle
			(at 2.999994 -2.999994 270)
			(size 1.1176 1.1176)
			(drill 0.749808)
			(layers "*.Cu" "*.Mask")
			(remove_unused_layers no)
			(net "GND")
			(clearance 0.1778)
			(thermal_gap 0.1778)
		)
	)
)
